# TIMECARD (Time Appliance Project (Time Card)) — schematic netlist excerpt (pin names and nets, part order shuffled) for the footprints in the layout excerpt that follows; sources: Cadence DE-HDL packaged netlist, KiCad conversion of R4006-B0001-02_R01.brd

SP43  NULL  pkg DUMMY  page 34
C280  CAPACITOR  10UF 6.3V 20%  pkg SMC_0402R_H022  page 20 : \1\ = VDD_BNO085 ; \2\ = SG

(kicad_pcb
	(version 20260206)
	(generator "pcbnew")
	(generator_version "10.0")
	(general
		(thickness 1.6)
		(legacy_teardrops no)
	)
	(paper "A4")
	(title_block
		(title "timecard-production-celestica-r4006 — R4006-B0001-02_R01.brd")
		(comment 1 "Time Appliance Project (Time Card) / footprints 97-98 of 1113")
	)
	(layers
		(0 "F.Cu" signal "TOP")
		(4 "In1.Cu" signal "L02_GND1")
		(6 "In2.Cu" signal "L03_SIG1")
		(8 "In3.Cu" signal "L04_GND2")
		(10 "In4.Cu" signal "L05_VCC1")
		(12 "In5.Cu" signal "L06_VCC2")
		(14 "In6.Cu" signal "L07_GND3")
		(16 "In7.Cu" signal "L08_SIG2")
		(18 "In8.Cu" signal "L09_GND4")
		(2 "B.Cu" signal "BOTTOM")
		(9 "F.Adhes" user "F.Adhesive")
		(11 "B.Adhes" user "B.Adhesive")
		(13 "F.Paste" user "Package Geometry/Pastemask Top")
		(15 "B.Paste" user "Package Geometry/Pastemask Bottom")
		(5 "F.SilkS" user "Ref Des/Silkscreen Top")
		(7 "B.SilkS" user "Ref Des/Silkscreen Bottom")
		(1 "F.Mask" user "Board Geometry/Soldermask Top")
		(3 "B.Mask" user "Board Geometry/Soldermask Bottom")
		(17 "Dwgs.User" user "User.Drawings")
		(19 "Cmts.User" user "User.Comments")
		(21 "Eco1.User" user "User.Eco1")
		(23 "Eco2.User" user "User.Eco2")
		(25 "Edge.Cuts" user "Board Geometry/Outline")
		(27 "Margin" user)
		(31 "F.CrtYd" user "Package Geometry/Place Bound Top")
		(29 "B.CrtYd" user "Package Geometry/Place Bound Bottom")
		(35 "F.Fab" user "Ref Des/Assembly Top")
		(33 "B.Fab" user "Ref Des/Assembly Bottom")
	)
	(footprint ""
		(layer "F.Cu")
		(at 85.974936 -64.3128 90)
		(property "Reference" "C280"
			(at 13.2842 -9.354566 90)
			(unlocked yes)
			(layer "F.SilkS")
			(effects
				(font
					(size 0.7874 0.5842)
					(thickness 0.1524)
				)
			)
		)
		(property "Value" "VAL*"
			(at 0.0762 2.067306 90)
			(unlocked yes)
			(layer "F.Fab")
			(hide yes)
			(effects
				(font
					(size 0.7874 0.5842)
					(thickness 0.1524)
				)
			)
		)
		(property "Device Type" "CAPACITOR-G105-0C106-BM,10UF,2A"
			(at 0.0508 1.127506 90)
			(unlocked yes)
			(layer "F.Fab")
			(hide yes)
			(effects
				(font
					(size 0.7874 0.5842)
					(thickness 0.1524)
				)
			)
		)
		(property "User Part Number" "PARTNUM*"
			(at 0.1016 4.023106 90)
			(unlocked yes)
			(layer "Cmts.User")
			(hide yes)
			(effects
				(font
					(size 0.7874 0.5842)
					(thickness 0.1524)
				)
			)
		)
		(property "Tolerance" "TOL*"
			(at 0.0762 3.032506 90)
			(unlocked yes)
			(layer "Cmts.User")
			(hide yes)
			(effects
				(font
					(size 0.7874 0.5842)
					(thickness 0.1524)
				)
			)
		)
		(duplicate_pad_numbers_are_jumpers no)
		(fp_line
			(start 1.143 -0.5588)
			(end -1.143 -0.5588)
			(stroke
				(width 0.1)
				(type default)
			)
			(layer "F.SilkS")
		)
		(fp_line
			(start -1.143 -0.5588)
			(end -1.143 0.5588)
			(stroke
				(width 0.1)
				(type default)
			)
			(layer "F.SilkS")
		)
		(fp_line
			(start 1.143 0.5588)
			(end 1.143 -0.5588)
			(stroke
				(width 0.1)
				(type default)
			)
			(layer "F.SilkS")
		)
		(fp_line
			(start -1.143 0.5588)
			(end 1.143 0.5588)
			(stroke
				(width 0.1)
				(type default)
			)
			(layer "F.SilkS")
		)
		(fp_rect
			(start -1.143 -0.5588)
			(end 1.143 0.5588)
			(stroke
				(width 0)
				(type default)
			)
			(fill no)
			(layer "F.CrtYd")
		)
		(fp_line
			(start 0.508 -0.3048)
			(end -0.508 -0.3048)
			(stroke
				(width 0.1)
				(type default)
			)
			(layer "F.Fab")
		)
		(fp_line
			(start -0.508 -0.3048)
			(end -0.508 0.3048)
			(stroke
				(width 0.1)
				(type default)
			)
			(layer "F.Fab")
		)
		(fp_line
			(start 0.508 0.3048)
			(end 0.508 -0.3048)
			(stroke
				(width 0.1)
				(type default)
			)
			(layer "F.Fab")
		)
		(fp_line
			(start -0.508 0.3048)
			(end 0.508 0.3048)
			(stroke
				(width 0.1)
				(type default)
			)
			(layer "F.Fab")
		)
		(pad "1" smd rect
			(at -0.5334 0 90)
			(size 0.7112 0.6096)
			(layers "F.Cu" "F.Mask" "F.Paste")
			(net "VDD_BNO085")
		)
		(pad "2" smd rect
			(at 0.5334 0 90)
			(size 0.7112 0.6096)
			(layers "F.Cu" "F.Mask" "F.Paste")
			(net "SG")
		)
		(zone
			(layer "F.Cu")
			(hatch none 0.5)
			(connect_pads
				(clearance 0)
			)
			(min_thickness 0.25)
			(keepout
				(tracks allowed)
				(vias not_allowed)
				(pads allowed)
				(copperpour not_allowed)
				(footprints allowed)
			)
			(placement
				(enabled no)
				(sheetname "")
			)
			(fill
				(thermal_gap 0.5)
				(thermal_bridge_width 0.5)
				(island_removal_mode 0)
			)
			(polygon
				(pts
					(xy 85.670136 -64.2366) (xy 86.279736 -64.2366) (xy 86.279736 -64.389) (xy 85.670136 -64.389)
				)
			)
		)
	)
	(footprint ""
		(layer "F.Cu")
		(at 44.958 -121.539)
		(property "Reference" "SP43"
			(at 0 0 0)
			(layer "F.SilkS")
			(hide yes)
			(effects
				(font
					(size 1.27 1.27)
				)
			)
		)
		(property "Value" ""
			(at 0 0 0)
			(layer "F.Fab")
			(effects
				(font
					(size 1.27 1.27)
				)
			)
		)
		(duplicate_pad_numbers_are_jumpers no)
	)
)
